FILE_TYPE = MACRO_DRAWING;
SET COLOR_WIRE YELLOW;
SET COLOR_PROP ORANGE;
SET COLOR_DOT WHITE;
SET COLOR_ARC YELLOW;
SET COLOR_BODY GREEN;
SET COLOR_NOTE PURPLE;
SET PROP_DISPLAY VALUE;
SET PAGE_NUMBER P240;
FORCEADD OFFPAGE..2
R 2
(-3475 -4125);
FORCEPROP 2 LAST $XR0 251 
J 0
(-3730 -4125);
DISPLAY 0.638298 (-3730 -4125);
PAINT MONO (-3730 -4125);
FORCEPROP 2 LAST $XR1 296 
J 0
(-3850 -4125);
DISPLAY 0.638298 (-3850 -4125);
PAINT MONO (-3850 -4125);
FORCEPROP 2 LAST PATH I1
J 0
(-3725 -4075);
DISPLAY 1.021277 (-3725 -4075);
DISPLAY INVISIBLE (-3725 -4075);
FORCEPROP 2 LAST CDS_LIB standard
J 2
(-3475 -4125);
PAINT MONO (-3475 -4125);
DISPLAY INVISIBLE (-3475 -4125);
FORCEPROP 1 LAST COMMENT_BODY TRUE
J 2
(-3430 -4220);
DISPLAY 0.872340 (-3430 -4220);
PAINT GREEN (-3430 -4220);
DISPLAY INVISIBLE (-3430 -4220);
FORCEPROP 1 LAST OFFPAGE TRUE
J 2
(-3800 -4250);
DISPLAY 0.872340 (-3800 -4250);
DISPLAY INVISIBLE (-3800 -4250);
FORCEADD OFFPAGE..1
(-2800 250);
FORCEPROP 2 LAST $XR2 305 
J 0
(-3322 250);
DISPLAY 0.638298 (-3322 250);
PAINT MONO (-3322 250);
FORCEPROP 2 LAST $XR1 233 
J 0
(-3202 250);
DISPLAY 0.638298 (-3202 250);
PAINT MONO (-3202 250);
FORCEPROP 2 LAST $XR0 170 
J 0
(-3082 250);
DISPLAY 0.638298 (-3082 250);
PAINT MONO (-3082 250);
FORCEPROP 1 LAST COMMENT_BODY TRUE
J 0
(-2675 150);
DISPLAY 0.872340 (-2675 150);
PAINT GREEN (-2675 150);
DISPLAY INVISIBLE (-2675 150);
FORCEPROP 1 LAST OFFPAGE TRUE
J 0
(-2475 125);
DISPLAY 0.872340 (-2475 125);
DISPLAY INVISIBLE (-2475 125);
FORCEPROP 2 LAST CDS_LIB standard
J 0
(-2800 250);
DISPLAY INVISIBLE (-2800 250);
FORCEPROP 2 LAST PATH I10
J 0
(-3075 300);
DISPLAY 1.021277 (-3075 300);
DISPLAY INVISIBLE (-3075 300);
FORCEADD Q_RES_4P_12..1
R 1
(-2400 -2525);
FORCEPROP 1 LAST PART_NUMBER SP_CS+001DFR10
J 0
(-2525 -2275);
DISPLAY 0.574468 (-2525 -2275);
PAINT GREEN (-2525 -2275);
DISPLAY INVISIBLE (-2525 -2275);
FORCEPROP 2 LAST WATTAGE 3W
J 0
(-2350 -2450);
DISPLAY 0.638298 (-2350 -2450);
FORCEPROP 2 LAST TOLERANCE 1%
J 0
(-2275 -2450);
DISPLAY 0.638298 (-2275 -2450);
FORCEPROP 2 LAST VALUE 0.001
J 0
(-2525 -2450);
DISPLAY 0.638298 (-2525 -2450);
FORCEPROP 2 LAST PART_TYPE SMLF
J 0
(-2525 -2400);
DISPLAY 0.638298 (-2525 -2400);
FORCEPROP 1 LAST MATERIAL CHIP
J 0
(-2525 -2325);
DISPLAY 0.574468 (-2525 -2325);
PAINT GREEN (-2525 -2325);
FORCEPROP 1 LAST LOCATION R1838
J 0
(-2525 -2225);
DISPLAY 0.680851 (-2525 -2225);
PAINT GREEN (-2525 -2225);
FORCEPROP 0 LASTPIN (-2525 -2525) $PN 1
J 2
(-2535 -2515);
DISPLAY 0.680851 (-2535 -2515);
PAINT MONO (-2535 -2515);
FORCEPROP 0 LASTPIN (-2275 -2525) $PN 2
J 0
(-2265 -2515);
DISPLAY 0.680851 (-2265 -2515);
PAINT MONO (-2265 -2515);
FORCEPROP 0 LASTPIN (-2425 -2625) $PN 3
R 1
J 2
(-2435 -2635);
DISPLAY 0.680851 (-2435 -2635);
PAINT MONO (-2435 -2635);
FORCEPROP 0 LASTPIN (-2375 -2625) $PN 4
R 1
J 2
(-2385 -2635);
DISPLAY 0.680851 (-2385 -2635);
PAINT MONO (-2385 -2635);
FORCEPROP 1 LAST PATH I11
R 1
J 0
(-2400 -2525);
DISPLAY 0.723404 (-2400 -2525);
PAINT GREEN (-2400 -2525);
DISPLAY INVISIBLE (-2400 -2525);
FORCEPROP 2 LAST CDS_LIB pure_quanta
R 1
J 0
(-2400 -2525);
DISPLAY INVISIBLE (-2400 -2525);
FORCEPROP 1 LAST CDS_LMAN_SYM_OUTLINE -50,75,50,-75
R 1
J 0
(-2400 -2525);
DISPLAY 0.468085 (-2400 -2525);
PAINT GREEN (-2400 -2525);
DISPLAY INVISIBLE (-2400 -2525);
FORCEPROP 1 LAST NEEDS_NO_SIZE TRUE
R 1
J 0
(-2399 -2525);
DISPLAY 0.468085 (-2399 -2525);
PAINT GREEN (-2399 -2525);
DISPLAY INVISIBLE (-2399 -2525);
FORCEPROP 0 LAST $SEC 1
R 1
J 0
(-2525 -2175);
DISPLAY 0.680851 (-2525 -2175);
PAINT MONO (-2525 -2175);
DISPLAY INVISIBLE (-2525 -2175);
FORCEPROP 0 LAST CDS_SEC 1
R 1
J 0
(-2850 -2675);
DISPLAY 1.021277 (-2850 -2675);
DISPLAY INVISIBLE (-2850 -2675);
FORCEADD OFFPAGE..2
(-1175 -2675);
FORCEPROP 2 LAST $XR0 251 
J 0
(-986 -2675);
DISPLAY 0.638298 (-986 -2675);
PAINT MONO (-986 -2675);
FORCEPROP 2 LAST $XR1 278 
J 0
(-866 -2675);
DISPLAY 0.638298 (-866 -2675);
PAINT MONO (-866 -2675);
FORCEPROP 2 LAST PATH I12
J 0
(-850 -2625);
DISPLAY 1.021277 (-850 -2625);
DISPLAY INVISIBLE (-850 -2625);
FORCEPROP 2 LAST CDS_LIB standard
J 0
(-1175 -2675);
PAINT MONO (-1175 -2675);
DISPLAY INVISIBLE (-1175 -2675);
FORCEPROP 1 LAST COMMENT_BODY TRUE
J 0
(-1220 -2770);
DISPLAY 0.872340 (-1220 -2770);
PAINT GREEN (-1220 -2770);
DISPLAY INVISIBLE (-1220 -2770);
FORCEPROP 1 LAST OFFPAGE TRUE
J 0
(-850 -2800);
DISPLAY 0.872340 (-850 -2800);
DISPLAY INVISIBLE (-850 -2800);
FORCEADD UNIVERSAL_POWER..1
(-1550 -2175);
FORCEPROP 3 LASTPIN (-1550 -2225) SIG_NAME P12V_S3_AUX_CPU0_NVDIMM\g
J 0
(-1540 -2215);
DISPLAY 0.659574 (-1540 -2215);
PAINT MONO (-1540 -2215);
DISPLAY INVISIBLE (-1540 -2215);
FORCEPROP 1 LAST HDL_POWER P12V_S3_AUX_CPU0_NVDIMM
J 1
(-1550 -2125);
DISPLAY 0.872340 (-1550 -2125);
PAINT GREEN (-1550 -2125);
FORCEPROP 1 LAST PATH I13
J 0
(-1500 -2150);
DISPLAY 0.872340 (-1500 -2150);
PAINT AQUA (-1500 -2150);
DISPLAY INVISIBLE (-1500 -2150);
FORCEPROP 2 LAST CDS_LIB logical_power
J 0
(-1550 -2175);
DISPLAY INVISIBLE (-1550 -2175);
FORCEADD UNIVERSAL_GND..1
(-1275 -525);
FORCEPROP 3 LASTPIN (-1275 -475) SIG_NAME GND\g
J 0
(-1265 -465);
DISPLAY 0.659574 (-1265 -465);
PAINT MONO (-1265 -465);
DISPLAY INVISIBLE (-1265 -465);
FORCEPROP 1 LAST HDL_POWER GND
J 1
(-1250 -600);
DISPLAY 0.872340 (-1250 -600);
PAINT GREEN (-1250 -600);
DISPLAY INVISIBLE (-1250 -600);
FORCEPROP 2 LAST CDS_LIB logical_power
J 0
(-1275 -525);
DISPLAY INVISIBLE (-1275 -525);
FORCEPROP 1 LAST PATH I14
J 0
(-1200 -525);
DISPLAY 0.872340 (-1200 -525);
PAINT AQUA (-1200 -525);
DISPLAY INVISIBLE (-1200 -525);
FORCEADD Q_CAP..1
(-1275 -225);
FORCEPROP 1 LAST PART_NUMBER CH4104K1B00
J 0
(-1225 -375);
DISPLAY 0.808511 (-1225 -375);
DISPLAY INVISIBLE (-1225 -375);
FORCEPROP 1 LAST MATERIAL EMPTY
J 0
(-1225 -325);
DISPLAY 0.638298 (-1225 -325);
FORCEPROP 1 LAST TOLERANCE 10%
J 0
(-1225 -275);
DISPLAY 0.638298 (-1225 -275);
FORCEPROP 1 LAST VOLTAGE 25V
J 0
(-1225 -225);
DISPLAY 0.638298 (-1225 -225);
FORCEPROP 1 LAST VALUE 0.1UF
J 0
(-1225 -175);
DISPLAY 0.638298 (-1225 -175);
FORCEPROP 2 LAST ROOM HSC1_BOM2
J 0
(-1225 -75);
DISPLAY 1.021277 (-1225 -75);
FORCEPROP 1 LAST PACK_TYPE 0402
J 0
(-1225 -375);
DISPLAY 0.638298 (-1225 -375);
FORCEPROP 1 LAST $LOCATION C2363
J 0
(-1225 -125);
DISPLAY 0.978723 (-1225 -125);
FORCEPROP 1 LASTPIN (-1275 -125) $PN 1
J 0
(-1265 -145);
DISPLAY 0.787234 (-1265 -145);
PAINT MONO (-1265 -145);
FORCEPROP 1 LASTPIN (-1275 -325) $PN 2
J 0
(-1265 -345);
DISPLAY 0.787234 (-1265 -345);
PAINT MONO (-1265 -345);
FORCEPROP 1 LAST PATH I15
J 0
(-1225 -75);
DISPLAY 0.978723 (-1225 -75);
PAINT WHITE (-1225 -75);
DISPLAY INVISIBLE (-1225 -75);
FORCEPROP 2 LAST CDS_LIB pure_quanta
J 0
(-1275 -225);
DISPLAY INVISIBLE (-1275 -225);
FORCEPROP 0 LAST CDS_LOCATION C2363
J 0
(-1225 -75);
DISPLAY 1.021277 (-1225 -75);
DISPLAY INVISIBLE (-1225 -75);
FORCEPROP 0 LAST $SEC 1
J 0
(-1225 -75);
DISPLAY 0.680851 (-1225 -75);
PAINT MONO (-1225 -75);
DISPLAY INVISIBLE (-1225 -75);
FORCEPROP 0 LAST CDS_SEC 1
J 0
(-1225 -75);
DISPLAY 1.021277 (-1225 -75);
DISPLAY INVISIBLE (-1225 -75);
FORCEADD Q_RES..2
(-1325 550);
FORCEPROP 1 LAST PART_NUMBER CS00002JB13
J 0
(-1250 500);
DISPLAY 0.404255 (-1250 500);
DISPLAY INVISIBLE (-1250 500);
FORCEPROP 1 LAST TOLERANCE 5%
J 0
(-1250 575);
DISPLAY 0.404255 (-1250 575);
FORCEPROP 2 LAST ROOM HSC1_BOM2
J 0
(-1250 675);
DISPLAY 1.021277 (-1250 675);
FORCEPROP 1 LAST WATTAGE 1/16W
J 0
(-1250 550);
DISPLAY 0.404255 (-1250 550);
FORCEPROP 1 LAST PACK_TYPE 0402LF
J 0
(-1250 475);
DISPLAY 0.404255 (-1250 475);
FORCEPROP 1 LAST MATERIAL EMPTY
J 0
(-1250 525);
DISPLAY 0.404255 (-1250 525);
FORCEPROP 1 LAST VALUE 0
J 0
(-1250 600);
DISPLAY 0.404255 (-1250 600);
FORCEPROP 1 LAST $LOCATION R4691
J 0
(-1250 625);
DISPLAY 0.978723 (-1250 625);
FORCEPROP 1 LASTPIN (-1325 650) $PN 1
J 0
(-1320 612);
DISPLAY 0.787234 (-1320 612);
PAINT MONO (-1320 612);
FORCEPROP 1 LASTPIN (-1325 450) $PN 2
J 0
(-1320 460);
DISPLAY 0.787234 (-1320 460);
PAINT MONO (-1320 460);
FORCEPROP 2 LAST CDS_LIB pure_quanta
J 0
(-1325 550);
DISPLAY INVISIBLE (-1325 550);
FORCEPROP 1 LAST PATH I16
J 0
(-1275 725);
DISPLAY 0.978723 (-1275 725);
PAINT WHITE (-1275 725);
DISPLAY INVISIBLE (-1275 725);
FORCEPROP 0 LAST CDS_LOCATION R4691
J 0
(-1250 675);
DISPLAY 1.021277 (-1250 675);
DISPLAY INVISIBLE (-1250 675);
FORCEPROP 0 LAST $SEC 1
J 0
(-1250 675);
DISPLAY 0.680851 (-1250 675);
PAINT MONO (-1250 675);
DISPLAY INVISIBLE (-1250 675);
FORCEPROP 0 LAST CDS_SEC 1
J 0
(-1250 675);
DISPLAY 1.021277 (-1250 675);
DISPLAY INVISIBLE (-1250 675);
FORCEADD UNIVERSAL_GND..1
(-2700 600);
FORCEPROP 3 LASTPIN (-2700 650) SIG_NAME GND\g
J 0
(-2690 660);
DISPLAY 0.659574 (-2690 660);
PAINT MONO (-2690 660);
DISPLAY INVISIBLE (-2690 660);
FORCEPROP 1 LAST PATH I17
J 0
(-2625 600);
DISPLAY 0.872340 (-2625 600);
PAINT AQUA (-2625 600);
DISPLAY INVISIBLE (-2625 600);
FORCEPROP 2 LAST CDS_LIB logical_power
J 0
(-2700 600);
DISPLAY INVISIBLE (-2700 600);
FORCEPROP 1 LAST HDL_POWER GND
J 1
(-2675 525);
DISPLAY 0.872340 (-2675 525);
PAINT GREEN (-2675 525);
DISPLAY INVISIBLE (-2675 525);
FORCEADD Q_RES..1
(-2125 725);
FORCEPROP 1 LAST PART_NUMBER CS24702FB06
J 0
(-2625 725);
DISPLAY 0.510638 (-2625 725);
DISPLAY INVISIBLE (-2625 725);
FORCEPROP 1 LAST MATERIAL EMPTY
J 0
(-1750 725);
DISPLAY 0.510638 (-1750 725);
PAINT RED (-1750 725);
FORCEPROP 1 LAST TOLERANCE 1%
J 0
(-1800 725);
DISPLAY 0.510638 (-1800 725);
FORCEPROP 1 LAST WATTAGE 1/16W
J 2
(-1800 725);
DISPLAY 0.510638 (-1800 725);
FORCEPROP 1 LAST VALUE 4.7K
J 2
(-1925 725);
DISPLAY 0.510638 (-1925 725);
FORCEPROP 1 LAST PACK_TYPE 0402LF
J 0
(-1625 725);
DISPLAY 0.510638 (-1625 725);
FORCEPROP 1 LAST $LOCATION R4688
J 0
(-2325 725);
DISPLAY 0.638298 (-2325 725);
FORCEPROP 1 LASTPIN (-2225 725) $PN 1
J 0
(-2213 737);
DISPLAY 0.787234 (-2213 737);
PAINT MONO (-2213 737);
FORCEPROP 1 LASTPIN (-2025 725) $PN 2
J 0
(-2063 737);
DISPLAY 0.787234 (-2063 737);
PAINT MONO (-2063 737);
FORCEPROP 1 LAST PATH I18
J 0
(-2175 875);
DISPLAY 0.978723 (-2175 875);
PAINT WHITE (-2175 875);
DISPLAY INVISIBLE (-2175 875);
FORCEPROP 2 LAST CDS_LIB pure_quanta
J 0
(-2125 725);
DISPLAY INVISIBLE (-2125 725);
FORCEPROP 0 LAST CDS_LOCATION R4688
J 0
(-2250 775);
DISPLAY 1.021277 (-2250 775);
DISPLAY INVISIBLE (-2250 775);
FORCEPROP 0 LAST $SEC 1
J 0
(-2250 775);
DISPLAY 0.680851 (-2250 775);
PAINT MONO (-2250 775);
DISPLAY INVISIBLE (-2250 775);
FORCEPROP 0 LAST CDS_SEC 1
J 0
(-2250 775);
DISPLAY 1.021277 (-2250 775);
DISPLAY INVISIBLE (-2250 775);
FORCEADD Q_RES..1
(-2125 800);
FORCEPROP 1 LAST PART_NUMBER CS24702FB06
J 0
(-2625 800);
DISPLAY 0.510638 (-2625 800);
DISPLAY INVISIBLE (-2625 800);
FORCEPROP 2 LAST ROOM HSC1_BOM2
J 0
(-2325 850);
DISPLAY 1.021277 (-2325 850);
FORCEPROP 1 LAST PACK_TYPE 0402LF
J 0
(-1625 800);
DISPLAY 0.510638 (-1625 800);
FORCEPROP 1 LAST MATERIAL EMPTY
J 0
(-1750 800);
DISPLAY 0.510638 (-1750 800);
FORCEPROP 1 LAST WATTAGE 1/16W
J 2
(-1800 800);
DISPLAY 0.510638 (-1800 800);
FORCEPROP 1 LAST TOLERANCE 1%
J 0
(-1800 800);
DISPLAY 0.510638 (-1800 800);
FORCEPROP 1 LAST VALUE 4.7K
J 2
(-1925 800);
DISPLAY 0.510638 (-1925 800);
FORCEPROP 1 LAST $LOCATION R4687
J 0
(-2325 800);
DISPLAY 0.638298 (-2325 800);
FORCEPROP 1 LASTPIN (-2225 800) $PN 1
J 0
(-2213 812);
DISPLAY 0.787234 (-2213 812);
PAINT MONO (-2213 812);
FORCEPROP 1 LASTPIN (-2025 800) $PN 2
J 0
(-2063 812);
DISPLAY 0.787234 (-2063 812);
PAINT MONO (-2063 812);
FORCEPROP 2 LAST CDS_LIB pure_quanta
J 0
(-2125 800);
DISPLAY INVISIBLE (-2125 800);
FORCEPROP 1 LAST PATH I19
J 0
(-2175 950);
DISPLAY 0.978723 (-2175 950);
PAINT WHITE (-2175 950);
DISPLAY INVISIBLE (-2175 950);
FORCEPROP 0 LAST CDS_LOCATION R4687
J 0
(-2250 850);
DISPLAY 1.021277 (-2250 850);
DISPLAY INVISIBLE (-2250 850);
FORCEPROP 0 LAST $SEC 1
J 0
(-2250 850);
DISPLAY 0.680851 (-2250 850);
PAINT MONO (-2250 850);
DISPLAY INVISIBLE (-2250 850);
FORCEPROP 0 LAST CDS_SEC 1
J 0
(-2250 850);
DISPLAY 1.021277 (-2250 850);
DISPLAY INVISIBLE (-2250 850);
FORCEADD UNIVERSAL_POWER..1
(-3275 -3625);
FORCEPROP 3 LASTPIN (-3275 -3675) SIG_NAME P12V_AUX\g
J 0
(-3265 -3665);
DISPLAY 0.659574 (-3265 -3665);
PAINT MONO (-3265 -3665);
DISPLAY INVISIBLE (-3265 -3665);
FORCEPROP 1 LAST HDL_POWER P12V_AUX
J 1
(-3275 -3575);
DISPLAY 0.872340 (-3275 -3575);
PAINT GREEN (-3275 -3575);
FORCEPROP 1 LAST PATH I2
J 0
(-3225 -3600);
DISPLAY 0.872340 (-3225 -3600);
PAINT AQUA (-3225 -3600);
DISPLAY INVISIBLE (-3225 -3600);
FORCEPROP 2 LAST CDS_LIB logical_power
J 0
(-3275 -3625);
DISPLAY INVISIBLE (-3275 -3625);
FORCEADD OFFPAGE..1
(375 -3900);
FORCEPROP 2 LAST $XR0 251 
J 0
(93 -3900);
DISPLAY 0.638298 (93 -3900);
PAINT MONO (93 -3900);
FORCEPROP 2 LAST $XR1 296 
J 0
(-27 -3900);
DISPLAY 0.638298 (-27 -3900);
PAINT MONO (-27 -3900);
FORCEPROP 2 LAST PATH I20
J 0
(100 -3850);
DISPLAY 1.021277 (100 -3850);
DISPLAY INVISIBLE (100 -3850);
FORCEPROP 2 LAST CDS_LIB standard
J 0
(375 -3900);
PAINT MONO (375 -3900);
DISPLAY INVISIBLE (375 -3900);
FORCEPROP 1 LAST COMMENT_BODY TRUE
J 0
(500 -4000);
DISPLAY 0.872340 (500 -4000);
PAINT GREEN (500 -4000);
DISPLAY INVISIBLE (500 -4000);
FORCEPROP 1 LAST OFFPAGE TRUE
J 0
(700 -4025);
DISPLAY 0.872340 (700 -4025);
PAINT GREEN (700 -4025);
DISPLAY INVISIBLE (700 -4025);
FORCEADD OFFPAGE..1
(375 -4050);
FORCEPROP 2 LAST $XR0 251 
J 0
(93 -4050);
DISPLAY 0.638298 (93 -4050);
PAINT MONO (93 -4050);
FORCEPROP 2 LAST $XR1 296 
J 0
(-27 -4050);
DISPLAY 0.638298 (-27 -4050);
PAINT MONO (-27 -4050);
FORCEPROP 2 LAST PATH I21
J 0
(100 -4000);
DISPLAY 1.021277 (100 -4000);
DISPLAY INVISIBLE (100 -4000);
FORCEPROP 2 LAST CDS_LIB standard
J 0
(375 -4050);
PAINT MONO (375 -4050);
DISPLAY INVISIBLE (375 -4050);
FORCEPROP 1 LAST COMMENT_BODY TRUE
J 0
(500 -4150);
DISPLAY 0.872340 (500 -4150);
PAINT GREEN (500 -4150);
DISPLAY INVISIBLE (500 -4150);
FORCEPROP 1 LAST OFFPAGE TRUE
J 0
(700 -4175);
DISPLAY 0.872340 (700 -4175);
PAINT GREEN (700 -4175);
DISPLAY INVISIBLE (700 -4175);
FORCEADD INA183A1IDBVR..1
(1850 -3975);
FORCEPROP 1 LAST PART_NUMBER AL000183000
J 0
(1681 -3716);
DISPLAY 0.723404 (1681 -3716);
PAINT GREEN (1681 -3716);
DISPLAY INVISIBLE (1681 -3716);
FORCEPROP 1 LAST MATERIAL EMPTY
J 0
(1681 -3843);
DISPLAY 0.723404 (1681 -3843);
PAINT GREEN (1681 -3843);
FORCEPROP 2 LAST VALUE INA183A1IDBVR
J 0
(1700 -3525);
DISPLAY 1.021277 (1700 -3525);
FORCEPROP 2 LAST PART_TYPE SMLF
J 0
(1700 -3475);
DISPLAY 1.021277 (1700 -3475);
FORCEPROP 1 LAST LOCATION U103
J 0
(1681 -3569);
DISPLAY 0.723404 (1681 -3569);
PAINT GREEN (1681 -3569);
FORCEPROP 2 LASTPIN (2175 -4000) $PN 1
J 0
(2185 -3990);
DISPLAY 0.680851 (2185 -3990);
PAINT MONO (2185 -3990);
FORCEPROP 2 LASTPIN (2175 -4050) $PN 2
J 0
(2185 -4040);
DISPLAY 0.680851 (2185 -4040);
PAINT MONO (2185 -4040);
FORCEPROP 2 LASTPIN (1525 -3900) $PN 5
J 2
(1515 -3890);
DISPLAY 0.680851 (1515 -3890);
PAINT MONO (1515 -3890);
FORCEPROP 2 LASTPIN (1525 -4050) $PN 4
J 2
(1515 -4040);
DISPLAY 0.680851 (1515 -4040);
PAINT MONO (1515 -4040);
FORCEPROP 2 LASTPIN (2175 -3900) $PN 3
J 0
(2185 -3890);
DISPLAY 0.680851 (2185 -3890);
PAINT MONO (2185 -3890);
FORCEPROP 2 LAST SEC_TYPE 
J 0
(1700 -3425);
DISPLAY 1.021277 (1700 -3425);
DISPLAY INVISIBLE (1700 -3425);
FORCEPROP 2 LAST CDS_LIB pure_quanta
J 0
(1850 -3975);
DISPLAY INVISIBLE (1850 -3975);
FORCEPROP 1 LAST CDS_LMAN_SYM_OUTLINE -175,125,175,-125
J 0
(1850 -3975);
DISPLAY 0.468085 (1850 -3975);
PAINT GREEN (1850 -3975);
DISPLAY INVISIBLE (1850 -3975);
FORCEPROP 1 LAST NEEDS_NO_SIZE TRUE
J 0
(1850 -3975);
DISPLAY 0.723404 (1850 -3975);
PAINT GREEN (1850 -3975);
DISPLAY INVISIBLE (1850 -3975);
FORCEPROP 1 LAST PATH I22
J 0
(1850 -3975);
DISPLAY 0.723404 (1850 -3975);
PAINT GREEN (1850 -3975);
DISPLAY INVISIBLE (1850 -3975);
FORCEPROP 2 LAST SEC 1
J 0
(1700 -3425);
DISPLAY 0.680851 (1700 -3425);
PAINT MONO (1700 -3425);
DISPLAY INVISIBLE (1700 -3425);
FORCEADD UNIVERSAL_GND..1
(2375 -4200);
FORCEPROP 3 LASTPIN (2375 -4150) SIG_NAME GND\g
J 0
(2385 -4140);
DISPLAY 0.659574 (2385 -4140);
PAINT MONO (2385 -4140);
DISPLAY INVISIBLE (2385 -4140);
FORCEPROP 1 LAST PATH I23
J 0
(2450 -4200);
DISPLAY 0.872340 (2450 -4200);
PAINT AQUA (2450 -4200);
DISPLAY INVISIBLE (2450 -4200);
FORCEPROP 2 LAST CDS_LIB logical_power
J 0
(2375 -4200);
PAINT MONO (2375 -4200);
DISPLAY INVISIBLE (2375 -4200);
FORCEPROP 1 LAST HDL_POWER GND
J 1
(2400 -4275);
DISPLAY 0.872340 (2400 -4275);
PAINT GREEN (2400 -4275);
DISPLAY INVISIBLE (2400 -4275);
FORCEADD OFFPAGE..2
(3025 -3900);
FORCEPROP 2 LAST $XR0 296 
J 0
(3214 -3900);
DISPLAY 0.638298 (3214 -3900);
PAINT MONO (3214 -3900);
FORCEPROP 2 LAST PATH I24
J 0
(3225 -3850);
DISPLAY 1.021277 (3225 -3850);
DISPLAY INVISIBLE (3225 -3850);
FORCEPROP 2 LAST CDS_LIB standard
J 0
(3025 -3900);
PAINT MONO (3025 -3900);
DISPLAY INVISIBLE (3025 -3900);
FORCEPROP 1 LAST OFFPAGE TRUE
J 0
(3350 -4025);
DISPLAY 0.872340 (3350 -4025);
DISPLAY INVISIBLE (3350 -4025);
FORCEPROP 1 LAST COMMENT_BODY TRUE
J 0
(2980 -3995);
DISPLAY 0.872340 (2980 -3995);
PAINT GREEN (2980 -3995);
DISPLAY INVISIBLE (2980 -3995);
FORCEADD OFFPAGE..1
(375 -2475);
FORCEPROP 2 LAST $XR0 251 
J 0
(93 -2475);
DISPLAY 0.638298 (93 -2475);
PAINT MONO (93 -2475);
FORCEPROP 2 LAST $XR1 278 
J 0
(-27 -2475);
DISPLAY 0.638298 (-27 -2475);
PAINT MONO (-27 -2475);
FORCEPROP 2 LAST PATH I25
J 0
(100 -2425);
DISPLAY 1.021277 (100 -2425);
DISPLAY INVISIBLE (100 -2425);
FORCEPROP 2 LAST CDS_LIB standard
J 0
(375 -2475);
PAINT MONO (375 -2475);
DISPLAY INVISIBLE (375 -2475);
FORCEPROP 1 LAST COMMENT_BODY TRUE
J 0
(500 -2575);
DISPLAY 0.872340 (500 -2575);
PAINT GREEN (500 -2575);
DISPLAY INVISIBLE (500 -2575);
FORCEPROP 1 LAST OFFPAGE TRUE
J 0
(700 -2600);
DISPLAY 0.872340 (700 -2600);
PAINT GREEN (700 -2600);
DISPLAY INVISIBLE (700 -2600);
FORCEADD OFFPAGE..1
(375 -2625);
FORCEPROP 2 LAST $XR0 251 
J 0
(93 -2625);
DISPLAY 0.638298 (93 -2625);
PAINT MONO (93 -2625);
FORCEPROP 2 LAST $XR1 278 
J 0
(-27 -2625);
DISPLAY 0.638298 (-27 -2625);
PAINT MONO (-27 -2625);
FORCEPROP 2 LAST PATH I26
J 0
(100 -2575);
DISPLAY 1.021277 (100 -2575);
DISPLAY INVISIBLE (100 -2575);
FORCEPROP 2 LAST CDS_LIB standard
J 0
(375 -2625);
PAINT MONO (375 -2625);
DISPLAY INVISIBLE (375 -2625);
FORCEPROP 1 LAST COMMENT_BODY TRUE
J 0
(500 -2725);
DISPLAY 0.872340 (500 -2725);
PAINT GREEN (500 -2725);
DISPLAY INVISIBLE (500 -2725);
FORCEPROP 1 LAST OFFPAGE TRUE
J 0
(700 -2750);
DISPLAY 0.872340 (700 -2750);
PAINT GREEN (700 -2750);
DISPLAY INVISIBLE (700 -2750);
FORCEADD UNIVERSAL_GND..1
(525 -400);
FORCEPROP 3 LASTPIN (525 -350) SIG_NAME GND\g
J 0
(535 -340);
DISPLAY 0.659574 (535 -340);
PAINT MONO (535 -340);
DISPLAY INVISIBLE (535 -340);
FORCEPROP 1 LAST PATH I28
J 0
(600 -400);
DISPLAY 0.872340 (600 -400);
PAINT AQUA (600 -400);
DISPLAY INVISIBLE (600 -400);
FORCEPROP 1 LAST HDL_POWER GND
J 1
(550 -475);
DISPLAY 0.872340 (550 -475);
PAINT GREEN (550 -475);
DISPLAY INVISIBLE (550 -475);
FORCEPROP 2 LAST CDS_LIB logical_power
J 0
(525 -400);
DISPLAY INVISIBLE (525 -400);
FORCEADD INA183A1IDBVR..1
(1850 -2550);
FORCEPROP 1 LAST PART_NUMBER AL000183000
J 0
(1681 -2291);
DISPLAY 0.723404 (1681 -2291);
PAINT GREEN (1681 -2291);
DISPLAY INVISIBLE (1681 -2291);
FORCEPROP 1 LAST MATERIAL EMPTY
J 0
(1681 -2418);
DISPLAY 0.723404 (1681 -2418);
PAINT GREEN (1681 -2418);
FORCEPROP 2 LAST PART_TYPE SMLF
J 0
(1700 -2050);
DISPLAY 1.021277 (1700 -2050);
FORCEPROP 2 LAST VALUE INA183A1IDBVR
J 0
(1700 -2100);
DISPLAY 1.021277 (1700 -2100);
FORCEPROP 1 LAST LOCATION U102
J 0
(1681 -2144);
DISPLAY 0.723404 (1681 -2144);
PAINT GREEN (1681 -2144);
FORCEPROP 2 LASTPIN (2175 -2575) $PN 1
J 0
(2185 -2565);
DISPLAY 0.680851 (2185 -2565);
PAINT MONO (2185 -2565);
FORCEPROP 2 LASTPIN (2175 -2625) $PN 2
J 0
(2185 -2615);
DISPLAY 0.680851 (2185 -2615);
PAINT MONO (2185 -2615);
FORCEPROP 2 LASTPIN (1525 -2475) $PN 5
J 2
(1515 -2465);
DISPLAY 0.680851 (1515 -2465);
PAINT MONO (1515 -2465);
FORCEPROP 2 LASTPIN (1525 -2625) $PN 4
J 2
(1515 -2615);
DISPLAY 0.680851 (1515 -2615);
PAINT MONO (1515 -2615);
FORCEPROP 2 LASTPIN (2175 -2475) $PN 3
J 0
(2185 -2465);
DISPLAY 0.680851 (2185 -2465);
PAINT MONO (2185 -2465);
FORCEPROP 2 LAST SEC_TYPE 
J 0
(1700 -2000);
DISPLAY 1.021277 (1700 -2000);
DISPLAY INVISIBLE (1700 -2000);
FORCEPROP 2 LAST CDS_LIB pure_quanta
J 0
(1850 -2550);
DISPLAY INVISIBLE (1850 -2550);
FORCEPROP 1 LAST NEEDS_NO_SIZE TRUE
J 0
(1850 -2550);
DISPLAY 0.723404 (1850 -2550);
PAINT GREEN (1850 -2550);
DISPLAY INVISIBLE (1850 -2550);
FORCEPROP 1 LAST CDS_LMAN_SYM_OUTLINE -175,125,175,-125
J 0
(1850 -2550);
DISPLAY 0.468085 (1850 -2550);
PAINT GREEN (1850 -2550);
DISPLAY INVISIBLE (1850 -2550);
FORCEPROP 1 LAST PATH I29
J 0
(1850 -2550);
DISPLAY 0.723404 (1850 -2550);
PAINT GREEN (1850 -2550);
DISPLAY INVISIBLE (1850 -2550);
FORCEPROP 2 LAST SEC 1
J 0
(1700 -2000);
DISPLAY 0.680851 (1700 -2000);
PAINT MONO (1700 -2000);
DISPLAY INVISIBLE (1700 -2000);
FORCEADD Q_RES_4P_12..1
R 1
(-2375 -3975);
FORCEPROP 1 LAST PART_NUMBER SP_CS+001DFR10
J 0
(-2500 -3725);
DISPLAY 0.574468 (-2500 -3725);
PAINT GREEN (-2500 -3725);
DISPLAY INVISIBLE (-2500 -3725);
FORCEPROP 2 LAST PART_TYPE SMLF
J 0
(-2500 -3850);
DISPLAY 0.638298 (-2500 -3850);
FORCEPROP 2 LAST VALUE 0.001
J 0
(-2500 -3900);
DISPLAY 0.638298 (-2500 -3900);
FORCEPROP 2 LAST WATTAGE 3W
J 0
(-2325 -3900);
DISPLAY 0.638298 (-2325 -3900);
FORCEPROP 2 LAST TOLERANCE 1%
J 0
(-2250 -3900);
DISPLAY 0.638298 (-2250 -3900);
FORCEPROP 1 LAST MATERIAL CHIP
J 0
(-2500 -3775);
DISPLAY 0.574468 (-2500 -3775);
PAINT GREEN (-2500 -3775);
FORCEPROP 1 LAST LOCATION R1837
J 0
(-2500 -3675);
DISPLAY 0.680851 (-2500 -3675);
PAINT GREEN (-2500 -3675);
FORCEPROP 0 LASTPIN (-2500 -3975) $PN 1
J 2
(-2510 -3965);
DISPLAY 0.680851 (-2510 -3965);
PAINT MONO (-2510 -3965);
FORCEPROP 0 LASTPIN (-2250 -3975) $PN 2
J 0
(-2240 -3965);
DISPLAY 0.680851 (-2240 -3965);
PAINT MONO (-2240 -3965);
FORCEPROP 0 LASTPIN (-2400 -4075) $PN 3
R 1
J 2
(-2410 -4085);
DISPLAY 0.680851 (-2410 -4085);
PAINT MONO (-2410 -4085);
FORCEPROP 0 LASTPIN (-2350 -4075) $PN 4
R 1
J 2
(-2360 -4085);
DISPLAY 0.680851 (-2360 -4085);
PAINT MONO (-2360 -4085);
FORCEPROP 1 LAST PATH I3
R 1
J 0
(-2375 -3975);
DISPLAY 0.723404 (-2375 -3975);
PAINT GREEN (-2375 -3975);
DISPLAY INVISIBLE (-2375 -3975);
FORCEPROP 2 LAST CDS_LIB pure_quanta
R 1
J 0
(-2375 -3975);
DISPLAY INVISIBLE (-2375 -3975);
FORCEPROP 1 LAST CDS_LMAN_SYM_OUTLINE -50,75,50,-75
R 1
J 0
(-2375 -3975);
DISPLAY 0.468085 (-2375 -3975);
PAINT GREEN (-2375 -3975);
DISPLAY INVISIBLE (-2375 -3975);
FORCEPROP 1 LAST NEEDS_NO_SIZE TRUE
R 1
J 0
(-2374 -3975);
DISPLAY 0.468085 (-2374 -3975);
PAINT GREEN (-2374 -3975);
DISPLAY INVISIBLE (-2374 -3975);
FORCEPROP 0 LAST $SEC 1
R 1
J 0
(-2500 -3625);
DISPLAY 0.680851 (-2500 -3625);
PAINT MONO (-2500 -3625);
DISPLAY INVISIBLE (-2500 -3625);
FORCEPROP 0 LAST CDS_SEC 1
R 1
J 0
(-2825 -4125);
DISPLAY 1.021277 (-2825 -4125);
DISPLAY INVISIBLE (-2825 -4125);
FORCEADD UNIVERSAL_GND..1
(2375 -2775);
FORCEPROP 3 LASTPIN (2375 -2725) SIG_NAME GND\g
J 0
(2385 -2715);
DISPLAY 0.659574 (2385 -2715);
PAINT MONO (2385 -2715);
DISPLAY INVISIBLE (2385 -2715);
FORCEPROP 1 LAST PATH I30
J 0
(2450 -2775);
DISPLAY 0.872340 (2450 -2775);
PAINT AQUA (2450 -2775);
DISPLAY INVISIBLE (2450 -2775);
FORCEPROP 2 LAST CDS_LIB logical_power
J 0
(2375 -2775);
PAINT MONO (2375 -2775);
DISPLAY INVISIBLE (2375 -2775);
FORCEPROP 1 LAST HDL_POWER GND
J 1
(2400 -2850);
DISPLAY 0.872340 (2400 -2850);
PAINT GREEN (2400 -2850);
DISPLAY INVISIBLE (2400 -2850);
FORCEADD OFFPAGE..2
(3025 -2475);
FORCEPROP 2 LAST $XR0 278 
J 0
(3214 -2475);
DISPLAY 0.638298 (3214 -2475);
PAINT MONO (3214 -2475);
FORCEPROP 2 LAST PATH I31
J 0
(3225 -2425);
DISPLAY 1.021277 (3225 -2425);
DISPLAY INVISIBLE (3225 -2425);
FORCEPROP 2 LAST CDS_LIB standard
J 0
(3025 -2475);
PAINT MONO (3025 -2475);
DISPLAY INVISIBLE (3025 -2475);
FORCEPROP 1 LAST OFFPAGE TRUE
J 0
(3350 -2600);
DISPLAY 0.872340 (3350 -2600);
DISPLAY INVISIBLE (3350 -2600);
FORCEPROP 1 LAST COMMENT_BODY TRUE
J 0
(2980 -2570);
DISPLAY 0.872340 (2980 -2570);
PAINT GREEN (2980 -2570);
DISPLAY INVISIBLE (2980 -2570);
FORCEADD UNIVERSAL_GND..1
(-700 525);
FORCEPROP 3 LASTPIN (-700 575) SIG_NAME GND\g
J 0
(-690 585);
DISPLAY 0.659574 (-690 585);
PAINT MONO (-690 585);
DISPLAY INVISIBLE (-690 585);
FORCEPROP 1 LAST PATH I32
J 0
(-625 525);
DISPLAY 0.872340 (-625 525);
PAINT AQUA (-625 525);
DISPLAY INVISIBLE (-625 525);
FORCEPROP 2 LAST CDS_LIB logical_power
J 0
(-700 525);
DISPLAY INVISIBLE (-700 525);
FORCEPROP 1 LAST HDL_POWER GND
J 1
(-675 450);
DISPLAY 0.872340 (-675 450);
PAINT GREEN (-675 450);
DISPLAY INVISIBLE (-675 450);
FORCEADD Q_CAP..1
(-700 800);
FORCEPROP 1 LAST PART_NUMBER CH4104K1B00
J 0
(-650 650);
DISPLAY 0.808511 (-650 650);
DISPLAY INVISIBLE (-650 650);
FORCEPROP 1 LAST PACK_TYPE 0402
J 0
(-650 650);
DISPLAY 0.638298 (-650 650);
FORCEPROP 2 LAST ROOM HSC1_BOM2
J 0
(-650 950);
DISPLAY 1.021277 (-650 950);
FORCEPROP 1 LAST TOLERANCE 10%
J 0
(-650 750);
DISPLAY 0.638298 (-650 750);
FORCEPROP 1 LAST MATERIAL EMPTY
J 0
(-650 700);
DISPLAY 0.638298 (-650 700);
FORCEPROP 1 LAST VALUE 0.1UF
J 0
(-650 850);
DISPLAY 0.638298 (-650 850);
FORCEPROP 1 LAST VOLTAGE 25V
J 0
(-650 800);
DISPLAY 0.638298 (-650 800);
FORCEPROP 1 LAST $LOCATION C2364
J 0
(-650 900);
DISPLAY 0.978723 (-650 900);
FORCEPROP 1 LASTPIN (-700 900) $PN 1
J 0
(-690 880);
DISPLAY 0.787234 (-690 880);
PAINT MONO (-690 880);
FORCEPROP 1 LASTPIN (-700 700) $PN 2
J 0
(-690 680);
DISPLAY 0.787234 (-690 680);
PAINT MONO (-690 680);
FORCEPROP 2 LAST CDS_LIB pure_quanta
J 0
(-700 800);
DISPLAY INVISIBLE (-700 800);
FORCEPROP 1 LAST PATH I33
J 0
(-650 950);
DISPLAY 0.978723 (-650 950);
PAINT WHITE (-650 950);
DISPLAY INVISIBLE (-650 950);
FORCEPROP 0 LAST CDS_LOCATION C2364
J 0
(-650 950);
DISPLAY 1.021277 (-650 950);
DISPLAY INVISIBLE (-650 950);
FORCEPROP 0 LAST $SEC 1
J 0
(-650 950);
DISPLAY 0.680851 (-650 950);
PAINT MONO (-650 950);
DISPLAY INVISIBLE (-650 950);
FORCEPROP 0 LAST CDS_SEC 1
J 0
(-650 950);
DISPLAY 1.021277 (-650 950);
DISPLAY INVISIBLE (-650 950);
FORCEADD UNIVERSAL_POWER..1
(-450 1200);
FORCEPROP 3 LASTPIN (-450 1150) SIG_NAME P3V3_AUX\g
J 0
(-440 1160);
DISPLAY 0.659574 (-440 1160);
PAINT MONO (-440 1160);
DISPLAY INVISIBLE (-440 1160);
FORCEPROP 1 LAST HDL_POWER P3V3_AUX
J 1
(-450 1250);
DISPLAY 0.872340 (-450 1250);
PAINT GREEN (-450 1250);
FORCEPROP 1 LAST PATH I34
J 0
(-400 1225);
DISPLAY 0.872340 (-400 1225);
PAINT AQUA (-400 1225);
DISPLAY INVISIBLE (-400 1225);
FORCEPROP 2 LAST CDS_LIB logical_power
J 0
(-450 1200);
DISPLAY INVISIBLE (-450 1200);
FORCEADD Q_RES..2
(1350 900);
FORCEPROP 1 LAST PART_NUMBER CS24702FB06
J 0
(1390 775);
DISPLAY 0.787234 (1390 775);
DISPLAY INVISIBLE (1390 775);
FORCEPROP 2 LAST ROOM HSC1_BOM2
J 0
(1400 1075);
DISPLAY 1.021277 (1400 1075);
FORCEPROP 1 LAST TOLERANCE 1%
J 0
(1395 925);
DISPLAY 0.787234 (1395 925);
FORCEPROP 1 LAST PACK_TYPE 0402LF
J 0
(1390 725);
DISPLAY 0.787234 (1390 725);
FORCEPROP 1 LAST WATTAGE 1/16W
J 0
(1390 875);
DISPLAY 0.787234 (1390 875);
FORCEPROP 1 LAST VALUE 4.7K
J 0
(1395 975);
DISPLAY 0.787234 (1395 975);
FORCEPROP 1 LAST MATERIAL EMPTY
J 0
(1390 825);
DISPLAY 0.787234 (1390 825);
FORCEPROP 1 LAST $LOCATION R4692
J 0
(1395 1025);
DISPLAY 0.978723 (1395 1025);
FORCEPROP 1 LASTPIN (1350 1000) $PN 1
J 0
(1355 962);
DISPLAY 0.787234 (1355 962);
PAINT MONO (1355 962);
FORCEPROP 1 LASTPIN (1350 800) $PN 2
J 0
(1355 810);
DISPLAY 0.787234 (1355 810);
PAINT MONO (1355 810);
FORCEPROP 2 LAST CDS_LIB pure_quanta
J 0
(1350 900);
DISPLAY INVISIBLE (1350 900);
FORCEPROP 1 LAST PATH I35
J 0
(1400 1075);
DISPLAY 0.978723 (1400 1075);
PAINT WHITE (1400 1075);
DISPLAY INVISIBLE (1400 1075);
FORCEPROP 0 LAST CDS_LOCATION R4692
J 0
(1400 1075);
DISPLAY 1.021277 (1400 1075);
DISPLAY INVISIBLE (1400 1075);
FORCEPROP 0 LAST $SEC 1
J 0
(1400 1075);
DISPLAY 0.680851 (1400 1075);
PAINT MONO (1400 1075);
DISPLAY INVISIBLE (1400 1075);
FORCEPROP 0 LAST CDS_SEC 1
J 0
(1400 1075);
DISPLAY 1.021277 (1400 1075);
DISPLAY INVISIBLE (1400 1075);
FORCEADD UNIVERSAL_POWER..1
(1350 1100);
FORCEPROP 3 LASTPIN (1350 1050) SIG_NAME P3V3_AUX\g
J 0
(1360 1060);
DISPLAY 0.659574 (1360 1060);
PAINT MONO (1360 1060);
DISPLAY INVISIBLE (1360 1060);
FORCEPROP 1 LAST HDL_POWER P3V3_AUX
J 1
(1350 1150);
DISPLAY 0.872340 (1350 1150);
PAINT GREEN (1350 1150);
FORCEPROP 1 LAST PATH I36
J 0
(1400 1125);
DISPLAY 0.872340 (1400 1125);
PAINT AQUA (1400 1125);
DISPLAY INVISIBLE (1400 1125);
FORCEPROP 2 LAST CDS_LIB logical_power
J 0
(1350 1100);
DISPLAY INVISIBLE (1350 1100);
FORCEADD Q_RES..1
(-1775 200);
FORCEPROP 1 LAST PART_NUMBER CS03322FB03
J 0
(-1900 250);
DISPLAY 0.638298 (-1900 250);
DISPLAY INVISIBLE (-1900 250);
FORCEPROP 1 LAST TOLERANCE 1%
J 0
(-1550 200);
DISPLAY 0.510638 (-1550 200);
FORCEPROP 1 LAST VALUE 33.2
J 2
(-1575 200);
DISPLAY 0.510638 (-1575 200);
FORCEPROP 1 LAST MATERIAL EMPTY
J 0
(-1475 200);
DISPLAY 0.510638 (-1475 200);
FORCEPROP 2 LAST ROOM HSC1_BOM2
J 0
(-1775 150);
DISPLAY 1.021277 (-1775 150);
FORCEPROP 1 LAST $LOCATION R4690
J 0
(-2025 200);
DISPLAY 0.787234 (-2025 200);
FORCEPROP 1 LASTPIN (-1875 200) $PN 1
J 0
(-1863 212);
DISPLAY 0.787234 (-1863 212);
FORCEPROP 1 LASTPIN (-1675 200) $PN 2
J 0
(-1713 212);
DISPLAY 0.787234 (-1713 212);
FORCEPROP 1 LAST PATH I37
J 0
(-1825 350);
DISPLAY 0.978723 (-1825 350);
PAINT WHITE (-1825 350);
DISPLAY INVISIBLE (-1825 350);
FORCEPROP 2 LAST CDS_LIB pure_quanta
J 0
(-1775 200);
PAINT MONO (-1775 200);
DISPLAY INVISIBLE (-1775 200);
FORCEPROP 1 LAST PACK_TYPE 0402LF
J 0
(-1425 200);
DISPLAY 0.638298 (-1425 200);
DISPLAY INVISIBLE (-1425 200);
FORCEPROP 1 LAST WATTAGE 1/16W
J 2
(-1575 300);
DISPLAY 0.638298 (-1575 300);
DISPLAY INVISIBLE (-1575 300);
FORCEPROP 2 LAST CDS_LOCATION R4690
J 0
(-1825 400);
DISPLAY 1.021277 (-1825 400);
DISPLAY INVISIBLE (-1825 400);
FORCEPROP 2 LAST $SEC 1
J 0
(-1825 400);
DISPLAY 0.680851 (-1825 400);
PAINT MONO (-1825 400);
DISPLAY INVISIBLE (-1825 400);
FORCEPROP 2 LAST CDS_SEC 1
J 0
(-1825 400);
DISPLAY 1.021277 (-1825 400);
DISPLAY INVISIBLE (-1825 400);
FORCEADD Q_RES..1
(-1775 250);
FORCEPROP 1 LAST PART_NUMBER CS03322FB03
J 0
(-1925 300);
DISPLAY 0.510638 (-1925 300);
DISPLAY INVISIBLE (-1925 300);
FORCEPROP 1 LAST MATERIAL EMPTY
J 0
(-1475 250);
DISPLAY 0.510638 (-1475 250);
FORCEPROP 1 LAST PACK_TYPE 0402LF
J 0
(-1925 350);
DISPLAY 0.510638 (-1925 350);
FORCEPROP 1 LAST WATTAGE 1/16W
J 2
(-1650 350);
DISPLAY 0.510638 (-1650 350);
FORCEPROP 2 LAST ROOM HSC1_BOM2
J 0
(-1650 375);
DISPLAY 1.021277 (-1650 375);
FORCEPROP 1 LAST TOLERANCE 1%
J 0
(-1550 250);
DISPLAY 0.510638 (-1550 250);
FORCEPROP 1 LAST VALUE 33.2
J 2
(-1575 250);
DISPLAY 0.510638 (-1575 250);
FORCEPROP 1 LAST $LOCATION R4689
J 0
(-2025 250);
DISPLAY 0.787234 (-2025 250);
FORCEPROP 1 LASTPIN (-1875 250) $PN 1
J 0
(-1863 262);
DISPLAY 0.787234 (-1863 262);
FORCEPROP 1 LASTPIN (-1675 250) $PN 2
J 0
(-1713 262);
DISPLAY 0.787234 (-1713 262);
FORCEPROP 1 LAST PATH I38
J 0
(-1825 400);
DISPLAY 0.978723 (-1825 400);
PAINT WHITE (-1825 400);
DISPLAY INVISIBLE (-1825 400);
FORCEPROP 2 LAST CDS_LIB pure_quanta
J 0
(-1775 250);
PAINT MONO (-1775 250);
DISPLAY INVISIBLE (-1775 250);
FORCEPROP 2 LAST CDS_LOCATION R4689
J 0
(-1825 450);
DISPLAY 1.021277 (-1825 450);
DISPLAY INVISIBLE (-1825 450);
FORCEPROP 2 LAST $SEC 1
J 0
(-1825 450);
DISPLAY 0.680851 (-1825 450);
PAINT MONO (-1825 450);
DISPLAY INVISIBLE (-1825 450);
FORCEPROP 2 LAST CDS_SEC 1
J 0
(-1825 450);
DISPLAY 1.021277 (-1825 450);
DISPLAY INVISIBLE (-1825 450);
FORCEADD INA230AIRGTR..1
(50 250);
FORCEPROP 1 LAST PART_NUMBER AL000230001
J 0
(-197 686);
DISPLAY 0.723404 (-197 686);
PAINT GREEN (-197 686);
DISPLAY INVISIBLE (-197 686);
FORCEPROP 2 LAST PART_TYPE SMLF
J 0
(-225 925);
DISPLAY 1.021277 (-225 925);
FORCEPROP 1 LAST MATERIAL EMPTY
J 0
(-197 559);
DISPLAY 0.723404 (-197 559);
PAINT GREEN (-197 559);
FORCEPROP 2 LAST VALUE INA230AIRGTR
J 0
(-225 875);
DISPLAY 1.021277 (-225 875);
FORCEPROP 0 LAST ROOM HSC1_BOM2
J 0
(-200 725);
DISPLAY 1.021277 (-200 725);
FORCEPROP 1 LAST LOCATION U331
J 0
(-197 833);
DISPLAY 0.723404 (-197 833);
PAINT GREEN (-197 833);
FORCEPROP 0 LASTPIN (-350 350) $PN 2
J 2
(-360 360);
DISPLAY 0.680851 (-360 360);
PAINT MONO (-360 360);
FORCEPROP 0 LASTPIN (-350 400) $PN 1
J 2
(-360 410);
DISPLAY 0.680851 (-360 410);
PAINT MONO (-360 410);
FORCEPROP 0 LASTPIN (450 500) $PN 3
J 0
(460 510);
DISPLAY 0.680851 (460 510);
PAINT MONO (460 510);
FORCEPROP 0 LASTPIN (-350 100) $PN 11
J 2
(-360 110);
DISPLAY 0.680851 (-360 110);
PAINT MONO (-360 110);
FORCEPROP 0 LASTPIN (450 50) $PN 10
J 0
(460 60);
DISPLAY 0.680851 (460 60);
PAINT MONO (460 60);
FORCEPROP 0 LASTPIN (-350 50) $PN 13
J 2
(-360 60);
DISPLAY 0.680851 (-360 60);
PAINT MONO (-360 60);
FORCEPROP 0 LASTPIN (-350 0) $PN 12
J 2
(-360 10);
DISPLAY 0.680851 (-360 10);
PAINT MONO (-360 10);
FORCEPROP 0 LASTPIN (450 400) $PN 6
J 0
(460 410);
DISPLAY 0.680851 (460 410);
PAINT MONO (460 410);
FORCEPROP 0 LASTPIN (450 350) $PN 7
J 0
(460 360);
DISPLAY 0.680851 (460 360);
PAINT MONO (460 360);
FORCEPROP 0 LASTPIN (450 300) $PN 8
J 0
(460 310);
DISPLAY 0.680851 (460 310);
PAINT MONO (460 310);
FORCEPROP 0 LASTPIN (450 250) $PN 14
J 0
(460 260);
DISPLAY 0.680851 (460 260);
PAINT MONO (460 260);
FORCEPROP 0 LASTPIN (450 200) $PN 15
J 0
(460 210);
DISPLAY 0.680851 (460 210);
PAINT MONO (460 210);
FORCEPROP 0 LASTPIN (450 150) $PN 16
J 0
(460 160);
DISPLAY 0.680851 (460 160);
PAINT MONO (460 160);
FORCEPROP 0 LASTPIN (-350 250) $PN 5
J 2
(-360 260);
DISPLAY 0.680851 (-360 260);
PAINT MONO (-360 260);
FORCEPROP 0 LASTPIN (-350 200) $PN 4
J 2
(-360 210);
DISPLAY 0.680851 (-360 210);
PAINT MONO (-360 210);
FORCEPROP 0 LASTPIN (450 0) $PN TH
J 0
(460 10);
DISPLAY 0.680851 (460 10);
PAINT MONO (460 10);
FORCEPROP 0 LASTPIN (-350 500) $PN 9
J 2
(-360 510);
DISPLAY 0.680851 (-360 510);
PAINT MONO (-360 510);
FORCEPROP 2 LAST CDS_LIB pure_quanta
J 0
(50 250);
DISPLAY INVISIBLE (50 250);
FORCEPROP 1 LAST PATH I39
J 0
(50 250);
DISPLAY 0.723404 (50 250);
PAINT GREEN (50 250);
DISPLAY INVISIBLE (50 250);
FORCEPROP 1 LAST CDS_LMAN_SYM_OUTLINE -250,300,250,-300
J 0
(50 250);
DISPLAY 0.468085 (50 250);
PAINT GREEN (50 250);
DISPLAY INVISIBLE (50 250);
FORCEPROP 1 LAST NEEDS_NO_SIZE TRUE
J 0
(50 250);
DISPLAY 0.723404 (50 250);
PAINT GREEN (50 250);
DISPLAY INVISIBLE (50 250);
FORCEPROP 0 LAST $SEC 1
J 0
(-225 975);
DISPLAY 0.680851 (-225 975);
PAINT MONO (-225 975);
DISPLAY INVISIBLE (-225 975);
FORCEPROP 0 LAST CDS_SEC 1
J 0
(-225 975);
DISPLAY 1.021277 (-225 975);
DISPLAY INVISIBLE (-225 975);
FORCEADD UNIVERSAL_POWER..1
(-1525 -3625);
FORCEPROP 3 LASTPIN (-1525 -3675) SIG_NAME P12V_S3_AUX_CPU1_NVDIMM\g
J 0
(-1515 -3665);
DISPLAY 0.659574 (-1515 -3665);
PAINT MONO (-1515 -3665);
DISPLAY INVISIBLE (-1515 -3665);
FORCEPROP 1 LAST HDL_POWER P12V_S3_AUX_CPU1_NVDIMM
J 1
(-1525 -3575);
DISPLAY 0.872340 (-1525 -3575);
PAINT GREEN (-1525 -3575);
FORCEPROP 1 LAST PATH I4
J 0
(-1475 -3600);
DISPLAY 0.872340 (-1475 -3600);
PAINT AQUA (-1475 -3600);
DISPLAY INVISIBLE (-1475 -3600);
FORCEPROP 2 LAST CDS_LIB logical_power
J 0
(-1525 -3625);
DISPLAY INVISIBLE (-1525 -3625);
FORCEADD OFFPAGE..2
(-1175 -4125);
FORCEPROP 2 LAST $XR0 251 
J 0
(-986 -4125);
DISPLAY 0.638298 (-986 -4125);
PAINT MONO (-986 -4125);
FORCEPROP 2 LAST $XR1 296 
J 0
(-866 -4125);
DISPLAY 0.638298 (-866 -4125);
PAINT MONO (-866 -4125);
FORCEPROP 2 LAST PATH I5
J 0
(-850 -4075);
DISPLAY 1.021277 (-850 -4075);
DISPLAY INVISIBLE (-850 -4075);
FORCEPROP 1 LAST OFFPAGE TRUE
J 0
(-850 -4250);
DISPLAY 0.872340 (-850 -4250);
DISPLAY INVISIBLE (-850 -4250);
FORCEPROP 1 LAST COMMENT_BODY TRUE
J 0
(-1220 -4220);
DISPLAY 0.872340 (-1220 -4220);
PAINT GREEN (-1220 -4220);
DISPLAY INVISIBLE (-1220 -4220);
FORCEPROP 2 LAST CDS_LIB standard
J 0
(-1175 -4125);
PAINT MONO (-1175 -4125);
DISPLAY INVISIBLE (-1175 -4125);
FORCEADD OFFPAGE..2
R 2
(-3500 -2675);
FORCEPROP 2 LAST $XR0 251 
J 0
(-3785 -2675);
DISPLAY 0.638298 (-3785 -2675);
PAINT MONO (-3785 -2675);
FORCEPROP 2 LAST $XR1 278 
J 0
(-3905 -2675);
DISPLAY 0.638298 (-3905 -2675);
PAINT MONO (-3905 -2675);
FORCEPROP 2 LAST PATH I6
J 0
(-3775 -2625);
DISPLAY 1.021277 (-3775 -2625);
DISPLAY INVISIBLE (-3775 -2625);
FORCEPROP 2 LAST CDS_LIB standard
J 2
(-3500 -2675);
PAINT MONO (-3500 -2675);
DISPLAY INVISIBLE (-3500 -2675);
FORCEPROP 1 LAST COMMENT_BODY TRUE
J 2
(-3455 -2770);
DISPLAY 0.872340 (-3455 -2770);
PAINT GREEN (-3455 -2770);
DISPLAY INVISIBLE (-3455 -2770);
FORCEPROP 1 LAST OFFPAGE TRUE
J 2
(-3825 -2800);
DISPLAY 0.872340 (-3825 -2800);
DISPLAY INVISIBLE (-3825 -2800);
FORCEADD UNIVERSAL_POWER..1
(-3300 -2175);
FORCEPROP 3 LASTPIN (-3300 -2225) SIG_NAME P12V_AUX\g
J 0
(-3290 -2215);
DISPLAY 0.659574 (-3290 -2215);
PAINT MONO (-3290 -2215);
DISPLAY INVISIBLE (-3290 -2215);
FORCEPROP 1 LAST HDL_POWER P12V_AUX
J 1
(-3300 -2125);
DISPLAY 0.872340 (-3300 -2125);
PAINT GREEN (-3300 -2125);
FORCEPROP 1 LAST PATH I7
J 0
(-3250 -2150);
DISPLAY 0.872340 (-3250 -2150);
PAINT AQUA (-3250 -2150);
DISPLAY INVISIBLE (-3250 -2150);
FORCEPROP 2 LAST CDS_LIB logical_power
J 0
(-3300 -2175);
DISPLAY INVISIBLE (-3300 -2175);
FORCEADD OFFPAGE..3
R 2
(-2775 200);
FORCEPROP 2 LAST $XR0 233 
J 0
(-3085 200);
DISPLAY 0.638298 (-3085 200);
PAINT MONO (-3085 200);
FORCEPROP 2 LAST $XR1 305 
J 0
(-3205 200);
DISPLAY 0.638298 (-3205 200);
PAINT MONO (-3205 200);
FORCEPROP 2 LAST $XR2 170 
J 0
(-3325 200);
DISPLAY 0.638298 (-3325 200);
PAINT MONO (-3325 200);
FORCEPROP 2 LAST PATH I8
J 0
(-3075 250);
DISPLAY 1.021277 (-3075 250);
DISPLAY INVISIBLE (-3075 250);
FORCEPROP 2 LAST CDS_LIB standard
J 2
(-2775 200);
PAINT MONO (-2775 200);
DISPLAY INVISIBLE (-2775 200);
FORCEPROP 1 LAST COMMENT_BODY TRUE
J 2
(-2725 100);
DISPLAY 0.872340 (-2725 100);
PAINT GREEN (-2725 100);
DISPLAY INVISIBLE (-2725 100);
FORCEPROP 1 LAST OFFPAGE TRUE
J 2
(-3100 75);
DISPLAY 0.872340 (-3100 75);
DISPLAY INVISIBLE (-3100 75);
FORCEADD OFFPAGE..1
(-2800 100);
FORCEPROP 2 LAST $XR0 305 
J 0
(-3082 100);
DISPLAY 0.638298 (-3082 100);
PAINT MONO (-3082 100);
FORCEPROP 2 LAST PATH I9
J 0
(-3075 150);
DISPLAY 1.021277 (-3075 150);
DISPLAY INVISIBLE (-3075 150);
FORCEPROP 2 LAST CDS_LIB standard
J 0
(-2800 100);
DISPLAY INVISIBLE (-2800 100);
FORCEPROP 1 LAST COMMENT_BODY TRUE
J 0
(-2675 0);
DISPLAY 0.872340 (-2675 0);
PAINT GREEN (-2675 0);
DISPLAY INVISIBLE (-2675 0);
FORCEPROP 1 LAST OFFPAGE TRUE
J 0
(-2475 -25);
DISPLAY 0.872340 (-2475 -25);
DISPLAY INVISIBLE (-2475 -25);
FORCEADD QUANTA_TITLE_BLOCK_C..1
(4350 -4700);
FORCEPROP 0 LAST CDS_CON_LAST_MODIFIED Fri Aug 25 14:04:21 2023
J 0
(2465 -4685);
DISPLAY INVISIBLE (2465 -4685);
FORCEPROP 2 LAST CUSTOM_TXT_CDS <XR_PAGE_TITLE>
J 0
(-3540 550);
DISPLAY 0.638298 (-3540 550);
PAINT PINK (-3540 550);
DISPLAY INVISIBLE (-3540 550);
FORCEPROP 2 LAST CUSTOM_TXT_CDS <CON_LAST_MODIFIED>
J 0
(2465 -4685);
DISPLAY 0.978723 (2465 -4685);
FORCEPROP 2 LAST CUSTOM_TXT_CDS <CON_PAGE_NUM> OF <CON_TOTAL_PAGES>
J 0
(3904 -4682);
DISPLAY 0.978723 (3904 -4682);
FORCEPROP 2 LAST CUSTOM_TXT_CDS <Q_REV>
J 0
(4166 -4597);
DISPLAY 1.212766 (4166 -4597);
FORCEPROP 2 LAST CUSTOM_TXT_CDS <Q_NUMBER>
J 0
(2947 -4597);
DISPLAY 1.212766 (2947 -4597);
FORCEPROP 2 LAST CUSTOM_TXT_CDS <Q_PROJ>
J 0
(1968 -4598);
DISPLAY 1.212766 (1968 -4598);
FORCEPROP 2 LAST CUSTOM_TXT_CDS <NAME_2>
J 0
(1175 -4650);
FORCEPROP 2 LAST CUSTOM_TXT_CDS <NAME_1>
J 0
(1175 -4525);
FORCEPROP 1 LAST Q_TITLE VOLTAGE SENSOR (2/2)
J 0
(-4966 -4649);
DISPLAY 2.446809 (-4966 -4649);
PAINT GREEN (-4966 -4649);
FORCEPROP 1 LAST Q_DEPT 
J 1
(587 -4651);
DISPLAY 1.957447 (587 -4651);
PAINT GREEN (587 -4651);
FORCEPROP 2 LAST PAGE_BORDER TRUE
J 0
(-3540 550);
DISPLAY 0.638298 (-3540 550);
PAINT PINK (-3540 550);
DISPLAY INVISIBLE (-3540 550);
FORCEPROP 1 LAST COMMENT_BODY TRUE
J 0
(4362 -4713);
DISPLAY 0.978723 (4362 -4713);
PAINT GREEN (4362 -4713);
DISPLAY INVISIBLE (4362 -4713);
FORCEPROP 1 LAST CDS_LMAN_SYM_OUTLINE -9475,6775,100,-125
J 0
(4350 -4700);
DISPLAY 0.468085 (4350 -4700);
PAINT GREEN (4350 -4700);
DISPLAY INVISIBLE (4350 -4700);
FORCEPROP 2 LAST CDS_LIB pure_quanta
J 0
(4350 -4700);
DISPLAY INVISIBLE (4350 -4700);
FORCEPROP 2 LAST CDS_XR_PAGE_TITLE CR-251 : @S9S_MB_2U_LIB.S9S_MB_2U(SCH_1):PAGE251
J 0
(-3540 550);
DISPLAY 0.638298 (-3540 550);
PAINT PINK (-3540 550);
DISPLAY INVISIBLE (-3540 550);
FORCEADD DNS..2
(-2100 725);
PAINT RED (-2100 725);
FORCEPROP 1 LAST COMMENT_BODY TRUE
R 1
J 0
(-2025 500);
DISPLAY 0.872340 (-2025 500);
PAINT GREEN (-2025 500);
DISPLAY INVISIBLE (-2025 500);
FORCEPROP 2 LAST CDS_LIB mstr_misc
J 0
(-2100 725);
DISPLAY INVISIBLE (-2100 725);
FORCEADD DNS..2
(-2100 800);
PAINT RED (-2100 800);
FORCEPROP 2 LAST CDS_LIB mstr_misc
J 0
(-2100 800);
DISPLAY INVISIBLE (-2100 800);
FORCEPROP 1 LAST COMMENT_BODY TRUE
R 1
J 0
(-2025 575);
DISPLAY 0.872340 (-2025 575);
PAINT GREEN (-2025 575);
DISPLAY INVISIBLE (-2025 575);
FORCEADD DNS..2
(-1800 225);
PAINT RED (-1800 225);
FORCEPROP 2 LAST CDS_LIB mstr_misc
J 0
(-1800 225);
DISPLAY INVISIBLE (-1800 225);
FORCEPROP 1 LAST COMMENT_BODY TRUE
R 1
J 0
(-1725 0);
DISPLAY 0.872340 (-1725 0);
PAINT GREEN (-1725 0);
DISPLAY INVISIBLE (-1725 0);
FORCEADD DNS..2
(-675 800);
PAINT RED (-675 800);
FORCEPROP 2 LAST CDS_LIB mstr_misc
J 0
(-675 800);
DISPLAY INVISIBLE (-675 800);
FORCEPROP 1 LAST COMMENT_BODY TRUE
R 1
J 0
(-600 575);
DISPLAY 0.872340 (-600 575);
PAINT GREEN (-600 575);
DISPLAY INVISIBLE (-600 575);
FORCEADD DNS..2
(0 375);
PAINT RED (0 375);
FORCEPROP 2 LAST CDS_LIB mstr_misc
J 0
(0 375);
DISPLAY INVISIBLE (0 375);
FORCEPROP 1 LAST COMMENT_BODY TRUE
R 1
J 0
(75 150);
DISPLAY 0.872340 (75 150);
PAINT GREEN (75 150);
DISPLAY INVISIBLE (75 150);
FORCEADD DNS..2
(1350 875);
PAINT RED (1350 875);
FORCEPROP 2 LAST CDS_LIB mstr_misc
J 0
(1350 875);
DISPLAY INVISIBLE (1350 875);
FORCEPROP 1 LAST COMMENT_BODY TRUE
R 1
J 0
(1425 650);
DISPLAY 0.872340 (1425 650);
PAINT GREEN (1425 650);
DISPLAY INVISIBLE (1425 650);
FORCEADD DNS..2
(-1325 525);
PAINT RED (-1325 525);
FORCEPROP 2 LAST CDS_LIB mstr_misc
J 0
(-1325 525);
DISPLAY INVISIBLE (-1325 525);
FORCEPROP 1 LAST COMMENT_BODY TRUE
R 1
J 0
(-1250 300);
DISPLAY 0.872340 (-1250 300);
PAINT GREEN (-1250 300);
DISPLAY INVISIBLE (-1250 300);
FORCEADD DNS..2
(1825 -2600);
PAINT RED (1825 -2600);
FORCEPROP 2 LAST CDS_LIB mstr_misc
J 0
(1825 -2600);
DISPLAY INVISIBLE (1825 -2600);
FORCEPROP 1 LAST COMMENT_BODY TRUE
R 1
J 0
(1900 -2825);
DISPLAY 0.872340 (1900 -2825);
PAINT GREEN (1900 -2825);
DISPLAY INVISIBLE (1900 -2825);
FORCEADD DNS..2
(1850 -4000);
PAINT RED (1850 -4000);
FORCEPROP 2 LAST CDS_LIB mstr_misc
J 0
(1850 -4000);
DISPLAY INVISIBLE (1850 -4000);
FORCEPROP 1 LAST COMMENT_BODY TRUE
R 1
J 0
(1925 -4225);
DISPLAY 0.872340 (1925 -4225);
PAINT GREEN (1925 -4225);
DISPLAY INVISIBLE (1925 -4225);
FORCEADD DNS..2
(-1800 175);
PAINT RED (-1800 175);
FORCEPROP 1 LAST COMMENT_BODY TRUE
R 1
J 0
(-1725 -50);
DISPLAY 0.872340 (-1725 -50);
PAINT GREEN (-1725 -50);
DISPLAY INVISIBLE (-1725 -50);
FORCEPROP 2 LAST CDS_LIB mstr_misc
J 0
(-1800 175);
DISPLAY INVISIBLE (-1800 175);
FORCEADD DNS..2
(-1275 -250);
PAINT RED (-1275 -250);
FORCEPROP 2 LAST CDS_LIB mstr_misc
J 0
(-1275 -250);
DISPLAY INVISIBLE (-1275 -250);
FORCEPROP 1 LAST COMMENT_BODY TRUE
R 1
J 0
(-1200 -475);
DISPLAY 0.872340 (-1200 -475);
PAINT GREEN (-1200 -475);
DISPLAY INVISIBLE (-1200 -475);
WIRE 16 -1 (1350 1000)(1350 1050);
WIRE 16 -1 (-450 1150)(-450 1025);
WIRE 16 -1 (-1550 -2225)(-1550 -2525);
WIRE 16 -1 (-3300 -2225)(-3300 -2525);
WIRE 16 -1 (-1525 -3675)(-1525 -3975);
WIRE 16 -1 (-3275 -3675)(-3275 -3975);
WIRE 16 -1 (-700 700)(-700 575);
WIRE 16 -1 (2375 -2625)(2375 -2725);
WIRE 16 -1 (2375 -2575)(2375 -2625);
WIRE 16 -1 (2175 -2625)(2375 -2625);
WIRE 16 -1 (2375 -4050)(2375 -4150);
WIRE 16 -1 (2375 -4000)(2375 -4050);
WIRE 16 -1 (2175 -4050)(2375 -4050);
WIRE 16 -1 (-2700 650)(-2700 725);
WIRE 16 -1 (-1275 -325)(-1275 -475);
WIRE 16 -1 (525 0)(525 -350);
WIRE 16 -1 (525 50)(525 0);
WIRE 16 -1 (450 0)(525 0);
WIRE 16 -1 (-400 500)(-350 500);
WIRE 16 -1 (-400 1025)(-400 500);
WIRE 16 -1 (-400 1025)(-450 1025);
WIRE 16 -1 (-700 1025)(-450 1025);
WIRE 16 -1 (-700 900)(-700 1025);
WIRE 16 -1 (-975 0)(-350 0);
FORCEPROP 2 LAST SIG_NAME NC_HSC_TYPE_VINM
J 0
(-935 10);
DISPLAY 0.638298 (-935 10);
PAINT WHITE (-935 10);
WIRE 16 -1 (-2750 100)(-1275 100);
WIRE 16 -1 (-350 100)(-1275 100);
FORCEPROP 2 LAST SIG_NAME HSC_TYPE_ADC
J 0
(-1260 110);
DISPLAY 0.638298 (-1260 110);
PAINT WHITE (-1260 110);
WIRE 16 -1 (-1275 -125)(-1275 100);
WIRE 16 -1 (-975 50)(-350 50);
FORCEPROP 2 LAST SIG_NAME NC_HSC_TYPE_VINP
J 0
(-935 60);
DISPLAY 0.638298 (-935 60);
PAINT WHITE (-935 60);
WIRE 16 -1 (-1675 200)(-1275 200);
WIRE 16 -1 (-1275 200)(-350 200);
FORCEPROP 2 LAST SIG_NAME SMB_HSC_TYPE_ADC_SDA
J 0
(-1260 210);
DISPLAY 0.680851 (-1260 210);
PAINT WHITE (-1260 210);
WIRE 16 -1 (-1275 450)(-1325 450);
WIRE 16 -1 (-1275 450)(-1275 200);
WIRE 16 -1 (-800 400)(-350 400);
WIRE 16 -1 (-800 800)(-2025 800);
FORCEPROP 2 LAST SIG_NAME HSC_TYPE_ADC_A1
J 0
(-1285 810);
DISPLAY 0.638298 (-1285 810);
PAINT WHITE (-1285 810);
WIRE 16 -1 (-800 800)(-800 400);
WIRE 16 -1 (1350 800)(1350 500);
WIRE 16 -1 (450 500)(1350 500);
FORCEPROP 2 LAST SIG_NAME TP_HSC_TYPE_ADC_ALERT
J 0
(590 510);
DISPLAY 0.638298 (590 510);
PAINT WHITE (590 510);
WIRE 16 -1 (-1550 -2525)(-2275 -2525);
WIRE 16 -1 (-2225 800)(-2700 800);
WIRE 16 -1 (-2700 800)(-2700 725);
WIRE 16 -1 (-2700 725)(-2225 725);
WIRE 16 -1 (-3275 -3975)(-2500 -3975);
WIRE 16 -1 (2175 -4000)(2375 -4000);
WIRE 16 -1 (2175 -2575)(2375 -2575);
WIRE 16 -1 (-1525 -3975)(-2250 -3975);
WIRE 16 -1 (-3300 -2525)(-2525 -2525);
WIRE 16 -1 (450 50)(525 50);
WIRE 16 -1 (450 150)(1075 150);
FORCEPROP 2 LAST SIG_NAME NC_HSC_TYPE_NC5
J 0
(590 160);
DISPLAY 0.638298 (590 160);
PAINT WHITE (590 160);
WIRE 16 -1 (450 200)(1075 200);
FORCEPROP 2 LAST SIG_NAME NC_HSC_TYPE_NC4
J 0
(590 210);
DISPLAY 0.638298 (590 210);
PAINT WHITE (590 210);
WIRE 16 -1 (450 250)(1075 250);
FORCEPROP 2 LAST SIG_NAME NC_HSC_TYPE_NC3
J 0
(590 260);
DISPLAY 0.638298 (590 260);
PAINT WHITE (590 260);
WIRE 16 -1 (450 300)(1075 300);
FORCEPROP 2 LAST SIG_NAME NC_HSC_TYPE_NC2
J 0
(590 310);
DISPLAY 0.638298 (590 310);
PAINT WHITE (590 310);
WIRE 16 -1 (450 350)(1075 350);
FORCEPROP 2 LAST SIG_NAME NC_HSC_TYPE_NC1
J 0
(590 360);
DISPLAY 0.638298 (590 360);
PAINT WHITE (590 360);
WIRE 16 -1 (450 400)(1075 400);
FORCEPROP 2 LAST SIG_NAME NC_HSC_TYPE_NC0
J 0
(590 410);
DISPLAY 0.638298 (590 410);
PAINT WHITE (590 410);
WIRE 16 -1 (-1675 250)(-350 250);
FORCEPROP 2 LAST SIG_NAME SMB_HSC_TYPE_ADC_SCL
J 0
(-1260 260);
DISPLAY 0.680851 (-1260 260);
PAINT WHITE (-1260 260);
WIRE 16 -1 (-1325 725)(-2025 725);
FORCEPROP 2 LAST SIG_NAME HSC_TYPE_ADC_A0
J 0
(-1335 735);
DISPLAY 0.638298 (-1335 735);
PAINT WHITE (-1335 735);
WIRE 16 -1 (-1325 650)(-1325 725);
WIRE 16 -1 (-900 725)(-1325 725);
WIRE 16 -1 (-900 725)(-900 350);
WIRE 16 -1 (-900 350)(-350 350);
WIRE 16 -1 (-1875 200)(-2725 200);
FORCEPROP 2 LAST SIG_NAME SMB_LM75_0_3V3AUX_SDA
J 0
(-2585 210);
DISPLAY 0.510638 (-2585 210);
PAINT WHITE (-2585 210);
WIRE 16 -1 (-1875 250)(-2750 250);
FORCEPROP 2 LAST SIG_NAME SMB_LM75_0_3V3AUX_SCL
J 0
(-2610 260);
DISPLAY 0.510638 (-2610 260);
PAINT WHITE (-2610 260);
WIRE 16 -1 (2975 -2475)(2175 -2475);
FORCEPROP 0 LAST CDS_PHYS_NET_NAME PVCCD_HV_CPU0_NVDIMM_ISENSE
J 0
(2265 -2444);
PAINT MONO (2265 -2444);
DISPLAY INVISIBLE (2265 -2444);
FORCEPROP 2 LAST SIG_NAME PVCCD_HV_CPU0_NVDIMM_ISENSE
J 0
(2365 -2465);
DISPLAY 0.446809 (2365 -2465);
PAINT WHITE (2365 -2465);
WIRE 16 -1 (1525 -3900)(425 -3900);
FORCEPROP 0 LAST CDS_PHYS_NET_NAME P12V_AUX_CPU1_DIMM_ISEN_P
J 0
(515 -3869);
PAINT MONO (515 -3869);
DISPLAY INVISIBLE (515 -3869);
FORCEPROP 2 LAST SIG_NAME P12V_AUX_CPU1_DIMM_ISEN_P
J 0
(615 -3890);
DISPLAY 0.446809 (615 -3890);
PAINT WHITE (615 -3890);
WIRE 16 -1 (1525 -4050)(425 -4050);
FORCEPROP 0 LAST CDS_PHYS_NET_NAME P12V_AUX_CPU1_DIMM_ISEN_N
J 0
(515 -4019);
PAINT MONO (515 -4019);
DISPLAY INVISIBLE (515 -4019);
FORCEPROP 2 LAST SIG_NAME P12V_AUX_CPU1_DIMM_ISEN_N
J 0
(615 -4040);
DISPLAY 0.446809 (615 -4040);
PAINT WHITE (615 -4040);
WIRE 16 -1 (1525 -2625)(425 -2625);
FORCEPROP 0 LAST CDS_PHYS_NET_NAME P12V_AUX_CPU0_DIMM_ISEN_N
J 0
(515 -2594);
PAINT MONO (515 -2594);
DISPLAY INVISIBLE (515 -2594);
FORCEPROP 2 LAST SIG_NAME P12V_AUX_CPU0_DIMM_ISEN_N
J 0
(615 -2615);
DISPLAY 0.446809 (615 -2615);
PAINT WHITE (615 -2615);
WIRE 16 -1 (-3450 -2675)(-2425 -2675);
FORCEPROP 0 LAST CDS_PHYS_NET_NAME P12V_AUX_CPU0_DIMM_ISEN_P
J 0
(-3360 -2644);
PAINT MONO (-3360 -2644);
DISPLAY INVISIBLE (-3360 -2644);
FORCEPROP 2 LAST SIG_NAME P12V_AUX_CPU0_DIMM_ISEN_P
J 0
(-3260 -2665);
DISPLAY 0.446809 (-3260 -2665);
PAINT WHITE (-3260 -2665);
WIRE 16 -1 (-2425 -2625)(-2425 -2675);
WIRE 16 -1 (1525 -2475)(425 -2475);
FORCEPROP 0 LAST CDS_PHYS_NET_NAME P12V_AUX_CPU0_DIMM_ISEN_P
J 0
(515 -2444);
PAINT MONO (515 -2444);
DISPLAY INVISIBLE (515 -2444);
FORCEPROP 2 LAST SIG_NAME P12V_AUX_CPU0_DIMM_ISEN_P
J 0
(615 -2465);
DISPLAY 0.446809 (615 -2465);
PAINT WHITE (615 -2465);
WIRE 16 -1 (2975 -3900)(2175 -3900);
FORCEPROP 0 LAST CDS_PHYS_NET_NAME PVCCD_HV_CPU1_NVDIMM_ISENSE
J 0
(2265 -3869);
PAINT MONO (2265 -3869);
DISPLAY INVISIBLE (2265 -3869);
FORCEPROP 2 LAST SIG_NAME PVCCD_HV_CPU1_NVDIMM_ISENSE
J 0
(2365 -3890);
DISPLAY 0.446809 (2365 -3890);
PAINT WHITE (2365 -3890);
WIRE 16 -1 (-2375 -2625)(-2375 -2675);
WIRE 16 -1 (-2375 -2675)(-1225 -2675);
FORCEPROP 0 LAST CDS_PHYS_NET_NAME P12V_AUX_CPU0_DIMM_ISEN_N
J 0
(-2185 -2644);
PAINT MONO (-2185 -2644);
DISPLAY INVISIBLE (-2185 -2644);
FORCEPROP 2 LAST SIG_NAME P12V_AUX_CPU0_DIMM_ISEN_N
J 0
(-2085 -2665);
DISPLAY 0.446809 (-2085 -2665);
PAINT WHITE (-2085 -2665);
WIRE 16 -1 (-2350 -4125)(-1225 -4125);
FORCEPROP 0 LAST CDS_PHYS_NET_NAME P12V_AUX_CPU1_DIMM_ISEN_N
J 0
(-2160 -4094);
PAINT MONO (-2160 -4094);
DISPLAY INVISIBLE (-2160 -4094);
FORCEPROP 2 LAST SIG_NAME P12V_AUX_CPU1_DIMM_ISEN_N
J 0
(-2060 -4115);
DISPLAY 0.446809 (-2060 -4115);
PAINT WHITE (-2060 -4115);
WIRE 16 -1 (-2350 -4075)(-2350 -4125);
WIRE 16 -1 (-3425 -4125)(-2400 -4125);
FORCEPROP 0 LAST CDS_PHYS_NET_NAME P12V_AUX_CPU1_DIMM_ISEN_P
J 0
(-3335 -4094);
PAINT MONO (-3335 -4094);
DISPLAY INVISIBLE (-3335 -4094);
FORCEPROP 2 LAST SIG_NAME P12V_AUX_CPU1_DIMM_ISEN_P
J 0
(-3235 -4115);
DISPLAY 0.446809 (-3235 -4115);
PAINT WHITE (-3235 -4115);
WIRE 16 -1 (-2400 -4075)(-2400 -4125);
DOT 1 (-450 1025);
DOT 1 (2375 -2625);
DOT 1 (2375 -4050);
DOT 1 (-1325 725);
DOT 1 (-2700 725);
DOT 1 (-1275 200);
DOT 1 (-1275 100);
DOT 1 (525 0);
FORCENOTE
ADDRESS : 0X84
(-400 -250) 0;
DISPLAY LEFT (-400 -250);
DISPLAY 1.340425 (-400 -250);
PAINT WHITE (-400 -250);
QUIT
